(kicad_pcb
	(version 20260206)
	(generator "pcbnew")
	(generator_version "10.0")
	(general
		(thickness 1.6)
		(legacy_teardrops no)
	)
	(paper "A4")
	(title_block
		(title "04192023_DAF0TMB3IC0_F0TG_MB_C_brd_V02_OCP.brd")
		(comment 1 "Grand Teton / footprints 6902-6908 of 8354")
	)
	(layers
		(0 "F.Cu" signal "TOP")
		(4 "In1.Cu" signal "GND")
		(6 "In2.Cu" signal "IN1")
		(8 "In3.Cu" signal "GND1")
		(10 "In4.Cu" signal "IN2")
		(12 "In5.Cu" signal "GND2")
		(14 "In6.Cu" signal "IN3")
		(16 "In7.Cu" signal "GND3")
		(18 "In8.Cu" signal "VCC")
		(20 "In9.Cu" signal "VCC1")
		(22 "In10.Cu" signal "GND4")
		(24 "In11.Cu" signal "IN4")
		(26 "In12.Cu" signal "GND5")
		(28 "In13.Cu" signal "IN5")
		(30 "In14.Cu" signal "GND6")
		(32 "In15.Cu" signal "IN6")
		(34 "In16.Cu" signal "GND7")
		(2 "B.Cu" signal "BOTTOM")
		(9 "F.Adhes" user "F.Adhesive")
		(11 "B.Adhes" user "B.Adhesive")
		(13 "F.Paste" user "Package Geometry/Pastemask Top")
		(15 "B.Paste" user "Package Geometry/Pastemask Bottom")
		(5 "F.SilkS" user "Ref Des/Silkscreen Top")
		(7 "B.SilkS" user "Ref Des/Silkscreen Bottom")
		(1 "F.Mask" user "Board Geometry/Soldermask Top")
		(3 "B.Mask" user "Board Geometry/Soldermask Bottom")
		(17 "Dwgs.User" user "User.Drawings")
		(19 "Cmts.User" user "User.Comments")
		(21 "Eco1.User" user "User.Eco1")
		(23 "Eco2.User" user "User.Eco2")
		(25 "Edge.Cuts" user "Board Geometry/Outline")
		(27 "Margin" user)
		(31 "F.CrtYd" user "Package Geometry/Place Bound Top")
		(29 "B.CrtYd" user "Package Geometry/Place Bound Bottom")
		(35 "F.Fab" user "Ref Des/Assembly Top")
		(33 "B.Fab" user "Ref Des/Assembly Bottom")
	)
	(footprint ""
		(layer "B.Cu")
		(at 399.796 -144.018 -90)
		(property "Reference" "R335"
			(at 0 0 90)
			(layer "B.SilkS")
			(hide yes)
			(effects
				(font
					(size 1.27 1.27)
				)
				(justify mirror)
			)
		)
		(property "Value" ""
			(at 0 0 90)
			(layer "B.Fab")
			(effects
				(font
					(size 1.27 1.27)
				)
				(justify mirror)
			)
		)
		(duplicate_pad_numbers_are_jumpers no)
		(fp_line
			(start -0.7874 0.4064)
			(end 0.7874 0.4064)
			(stroke
				(width 0.1524)
				(type default)
			)
			(layer "B.SilkS")
		)
		(fp_line
			(start 0.7874 0.4064)
			(end 0.7874 -0.4064)
			(stroke
				(width 0.1524)
				(type default)
			)
			(layer "B.SilkS")
		)
		(fp_line
			(start -0.7874 -0.4064)
			(end -0.7874 0.4064)
			(stroke
				(width 0.1524)
				(type default)
			)
			(layer "B.SilkS")
		)
		(fp_line
			(start 0.7874 -0.4064)
			(end -0.7874 -0.4064)
			(stroke
				(width 0.1524)
				(type default)
			)
			(layer "B.SilkS")
		)
		(fp_line
			(start -0.67945 0.3048)
			(end -0.120396 0.3048)
			(stroke
				(width 0.1)
				(type default)
			)
			(layer "B.Fab")
		)
		(fp_line
			(start -0.120396 0.3048)
			(end -0.120396 0.2794)
			(stroke
				(width 0.1)
				(type default)
			)
			(layer "B.Fab")
		)
		(fp_line
			(start 0.12065 0.3048)
			(end 0.67945 0.3048)
			(stroke
				(width 0.1)
				(type default)
			)
			(layer "B.Fab")
		)
		(fp_line
			(start 0.67945 0.3048)
			(end 0.67945 -0.305054)
			(stroke
				(width 0.1)
				(type default)
			)
			(layer "B.Fab")
		)
		(fp_line
			(start -0.120396 0.2794)
			(end 0.12065 0.2794)
			(stroke
				(width 0.1)
				(type default)
			)
			(layer "B.Fab")
		)
		(fp_line
			(start 0.12065 0.2794)
			(end 0.12065 0.3048)
			(stroke
				(width 0.1)
				(type default)
			)
			(layer "B.Fab")
		)
		(fp_line
			(start -0.12065 -0.2794)
			(end -0.12065 -0.3048)
			(stroke
				(width 0.1)
				(type default)
			)
			(layer "B.Fab")
		)
		(fp_line
			(start 0.12065 -0.2794)
			(end -0.12065 -0.2794)
			(stroke
				(width 0.1)
				(type default)
			)
			(layer "B.Fab")
		)
		(fp_line
			(start -0.67945 -0.3048)
			(end -0.67945 0.3048)
			(stroke
				(width 0.1)
				(type default)
			)
			(layer "B.Fab")
		)
		(fp_line
			(start -0.12065 -0.3048)
			(end -0.67945 -0.3048)
			(stroke
				(width 0.1)
				(type default)
			)
			(layer "B.Fab")
		)
		(fp_line
			(start 0.12065 -0.305054)
			(end 0.12065 -0.2794)
			(stroke
				(width 0.1)
				(type default)
			)
			(layer "B.Fab")
		)
		(fp_line
			(start 0.67945 -0.305054)
			(end 0.12065 -0.305054)
			(stroke
				(width 0.1)
				(type default)
			)
			(layer "B.Fab")
		)
		(pad "1" smd circle
			(at 0.40005 0 90)
			(size 0 0)
			(layers "B.Cu" "B.Mask" "B.Paste")
			(net "P12V_AUX")
		)
		(pad "2" smd circle
			(at -0.40005 0 90)
			(size 0 0)
			(layers "B.Cu" "B.Mask" "B.Paste")
			(net "VR_P5V_EN_D_R")
		)
	)
	(footprint ""
		(layer "B.Cu")
		(at 396.906242 -416.899344 90)
		(property "Reference" "C6614"
			(at 0 0 90)
			(layer "B.SilkS")
			(hide yes)
			(effects
				(font
					(size 1.27 1.27)
				)
				(justify mirror)
			)
		)
		(property "Value" ""
			(at 0 0 90)
			(layer "B.Fab")
			(effects
				(font
					(size 1.27 1.27)
				)
				(justify mirror)
			)
		)
		(duplicate_pad_numbers_are_jumpers no)
		(fp_line
			(start 0.299974 -0.150114)
			(end -0.299974 -0.150114)
			(stroke
				(width 0.1)
				(type default)
			)
			(layer "B.Fab")
		)
		(fp_line
			(start -0.299974 -0.150114)
			(end -0.299974 0.150114)
			(stroke
				(width 0.1)
				(type default)
			)
			(layer "B.Fab")
		)
		(fp_line
			(start 0.299974 0.150114)
			(end 0.299974 -0.150114)
			(stroke
				(width 0.1)
				(type default)
			)
			(layer "B.Fab")
		)
		(fp_line
			(start -0.299974 0.150114)
			(end 0.299974 0.150114)
			(stroke
				(width 0.1)
				(type default)
			)
			(layer "B.Fab")
		)
		(pad "1" smd rect
			(at 0.2667 0 270)
			(size 0.3048 0.381)
			(layers "B.Cu" "B.Mask" "B.Paste")
			(net "P5E_CPU0_P3_TX_BUF_C_DN<8>")
		)
		(pad "2" smd rect
			(at -0.2667 0 270)
			(size 0.3048 0.381)
			(layers "B.Cu" "B.Mask" "B.Paste")
			(net "P5E_CPU0_P3_TX_BUF_DN<8>")
		)
	)
	(footprint ""
		(layer "B.Cu")
		(at 56.99125 -390.560052 90)
		(property "Reference" "C119"
			(at 0 0 90)
			(layer "B.SilkS")
			(hide yes)
			(effects
				(font
					(size 1.27 1.27)
				)
				(justify mirror)
			)
		)
		(property "Value" ""
			(at 0 0 90)
			(layer "B.Fab")
			(effects
				(font
					(size 1.27 1.27)
				)
				(justify mirror)
			)
		)
		(duplicate_pad_numbers_are_jumpers no)
		(fp_line
			(start 0.7874 -0.4064)
			(end -0.7874 -0.4064)
			(stroke
				(width 0.1524)
				(type default)
			)
			(layer "B.SilkS")
		)
		(fp_line
			(start -0.7874 -0.4064)
			(end -0.7874 0.4064)
			(stroke
				(width 0.1524)
				(type default)
			)
			(layer "B.SilkS")
		)
		(fp_line
			(start 0.7874 0.4064)
			(end 0.7874 -0.4064)
			(stroke
				(width 0.1524)
				(type default)
			)
			(layer "B.SilkS")
		)
		(fp_line
			(start -0.7874 0.4064)
			(end 0.7874 0.4064)
			(stroke
				(width 0.1524)
				(type default)
			)
			(layer "B.SilkS")
		)
		(fp_line
			(start 0.67945 -0.305054)
			(end 0.12065 -0.305054)
			(stroke
				(width 0.1)
				(type default)
			)
			(layer "B.Fab")
		)
		(fp_line
			(start 0.12065 -0.305054)
			(end 0.12065 -0.2794)
			(stroke
				(width 0.1)
				(type default)
			)
			(layer "B.Fab")
		)
		(fp_line
			(start -0.12065 -0.3048)
			(end -0.67945 -0.3048)
			(stroke
				(width 0.1)
				(type default)
			)
			(layer "B.Fab")
		)
		(fp_line
			(start -0.67945 -0.3048)
			(end -0.67945 0.3048)
			(stroke
				(width 0.1)
				(type default)
			)
			(layer "B.Fab")
		)
		(fp_line
			(start 0.12065 -0.2794)
			(end -0.12065 -0.2794)
			(stroke
				(width 0.1)
				(type default)
			)
			(layer "B.Fab")
		)
		(fp_line
			(start -0.12065 -0.2794)
			(end -0.12065 -0.3048)
			(stroke
				(width 0.1)
				(type default)
			)
			(layer "B.Fab")
		)
		(fp_line
			(start 0.12065 0.2794)
			(end 0.12065 0.3048)
			(stroke
				(width 0.1)
				(type default)
			)
			(layer "B.Fab")
		)
		(fp_line
			(start -0.120396 0.2794)
			(end 0.12065 0.2794)
			(stroke
				(width 0.1)
				(type default)
			)
			(layer "B.Fab")
		)
		(fp_line
			(start 0.67945 0.3048)
			(end 0.67945 -0.305054)
			(stroke
				(width 0.1)
				(type default)
			)
			(layer "B.Fab")
		)
		(fp_line
			(start 0.12065 0.3048)
			(end 0.67945 0.3048)
			(stroke
				(width 0.1)
				(type default)
			)
			(layer "B.Fab")
		)
		(fp_line
			(start -0.120396 0.3048)
			(end -0.120396 0.2794)
			(stroke
				(width 0.1)
				(type default)
			)
			(layer "B.Fab")
		)
		(fp_line
			(start -0.67945 0.3048)
			(end -0.120396 0.3048)
			(stroke
				(width 0.1)
				(type default)
			)
			(layer "B.Fab")
		)
		(pad "1" smd circle
			(at 0.40005 0 270)
			(size 0 0)
			(layers "B.Cu" "B.Mask" "B.Paste")
			(net "P1V8_CPU1_RT0_1A")
		)
		(pad "2" smd circle
			(at -0.40005 0 270)
			(size 0 0)
			(layers "B.Cu" "B.Mask" "B.Paste")
			(net "GND")
		)
	)
	(footprint ""
		(layer "B.Cu")
		(at 107.863386 -268.418564)
		(property "Reference" "C2374"
			(at 0 0 0)
			(layer "B.SilkS")
			(hide yes)
			(effects
				(font
					(size 1.27 1.27)
				)
				(justify mirror)
			)
		)
		(property "Value" ""
			(at 0 0 0)
			(layer "B.Fab")
			(effects
				(font
					(size 1.27 1.27)
				)
				(justify mirror)
			)
		)
		(duplicate_pad_numbers_are_jumpers no)
		(fp_line
			(start -0.7874 -0.4064)
			(end -0.7874 0.4064)
			(stroke
				(width 0.1524)
				(type default)
			)
			(layer "B.SilkS")
		)
		(fp_line
			(start -0.7874 0.4064)
			(end 0.7874 0.4064)
			(stroke
				(width 0.1524)
				(type default)
			)
			(layer "B.SilkS")
		)
		(fp_line
			(start 0.7874 -0.4064)
			(end -0.7874 -0.4064)
			(stroke
				(width 0.1524)
				(type default)
			)
			(layer "B.SilkS")
		)
		(fp_line
			(start 0.7874 0.4064)
			(end 0.7874 -0.4064)
			(stroke
				(width 0.1524)
				(type default)
			)
			(layer "B.SilkS")
		)
		(fp_line
			(start -0.67945 -0.3048)
			(end -0.67945 0.3048)
			(stroke
				(width 0.1)
				(type default)
			)
			(layer "B.Fab")
		)
		(fp_line
			(start -0.67945 0.3048)
			(end -0.120396 0.3048)
			(stroke
				(width 0.1)
				(type default)
			)
			(layer "B.Fab")
		)
		(fp_line
			(start -0.12065 -0.3048)
			(end -0.67945 -0.3048)
			(stroke
				(width 0.1)
				(type default)
			)
			(layer "B.Fab")
		)
		(fp_line
			(start -0.12065 -0.2794)
			(end -0.12065 -0.3048)
			(stroke
				(width 0.1)
				(type default)
			)
			(layer "B.Fab")
		)
		(fp_line
			(start -0.120396 0.2794)
			(end 0.12065 0.2794)
			(stroke
				(width 0.1)
				(type default)
			)
			(layer "B.Fab")
		)
		(fp_line
			(start -0.120396 0.3048)
			(end -0.120396 0.2794)
			(stroke
				(width 0.1)
				(type default)
			)
			(layer "B.Fab")
		)
		(fp_line
			(start 0.12065 -0.305054)
			(end 0.12065 -0.2794)
			(stroke
				(width 0.1)
				(type default)
			)
			(layer "B.Fab")
		)
		(fp_line
			(start 0.12065 -0.2794)
			(end -0.12065 -0.2794)
			(stroke
				(width 0.1)
				(type default)
			)
			(layer "B.Fab")
		)
		(fp_line
			(start 0.12065 0.2794)
			(end 0.12065 0.3048)
			(stroke
				(width 0.1)
				(type default)
			)
			(layer "B.Fab")
		)
		(fp_line
			(start 0.12065 0.3048)
			(end 0.67945 0.3048)
			(stroke
				(width 0.1)
				(type default)
			)
			(layer "B.Fab")
		)
		(fp_line
			(start 0.67945 -0.305054)
			(end 0.12065 -0.305054)
			(stroke
				(width 0.1)
				(type default)
			)
			(layer "B.Fab")
		)
		(fp_line
			(start 0.67945 0.3048)
			(end 0.67945 -0.305054)
			(stroke
				(width 0.1)
				(type default)
			)
			(layer "B.Fab")
		)
		(pad "1" smd circle
			(at 0.40005 0 180)
			(size 0 0)
			(layers "B.Cu" "B.Mask" "B.Paste")
			(net "PVDDCR_CPU1_P1")
		)
		(pad "2" smd circle
			(at -0.40005 0 180)
			(size 0 0)
			(layers "B.Cu" "B.Mask" "B.Paste")
			(net "GND")
		)
	)
	(footprint ""
		(layer "B.Cu")
		(at 107.034838 -389.673084 90)
		(property "Reference" "C474"
			(at 0 0 90)
			(layer "B.SilkS")
			(hide yes)
			(effects
				(font
					(size 1.27 1.27)
				)
				(justify mirror)
			)
		)
		(property "Value" ""
			(at 0 0 90)
			(layer "B.Fab")
			(effects
				(font
					(size 1.27 1.27)
				)
				(justify mirror)
			)
		)
		(duplicate_pad_numbers_are_jumpers no)
		(fp_line
			(start 1.524 -0.762)
			(end -1.524 -0.762)
			(stroke
				(width 0.1524)
				(type default)
			)
			(layer "B.SilkS")
		)
		(fp_line
			(start -1.524 -0.762)
			(end -1.524 0.762)
			(stroke
				(width 0.1524)
				(type default)
			)
			(layer "B.SilkS")
		)
		(fp_line
			(start 1.524 0.762)
			(end 1.524 -0.762)
			(stroke
				(width 0.1524)
				(type default)
			)
			(layer "B.SilkS")
		)
		(fp_line
			(start -1.524 0.762)
			(end 1.524 0.762)
			(stroke
				(width 0.1524)
				(type default)
			)
			(layer "B.SilkS")
		)
		(fp_line
			(start 1.1049 -0.724916)
			(end 1.1049 0.724916)
			(stroke
				(width 0.1)
				(type default)
			)
			(layer "B.Fab")
		)
		(fp_line
			(start -1.1049 -0.724916)
			(end 1.1049 -0.724916)
			(stroke
				(width 0.1)
				(type default)
			)
			(layer "B.Fab")
		)
		(fp_line
			(start 1.1049 0.724916)
			(end -1.1049 0.724916)
			(stroke
				(width 0.1)
				(type default)
			)
			(layer "B.Fab")
		)
		(fp_line
			(start -1.1049 0.724916)
			(end -1.1049 -0.724916)
			(stroke
				(width 0.1)
				(type default)
			)
			(layer "B.Fab")
		)
		(pad "1" smd rect
			(at 0.889 0 90)
			(size 1.016 1.27)
			(layers "B.Cu" "B.Mask" "B.Paste")
			(net "P0V9_CPU1_RT_2D")
		)
		(pad "2" smd rect
			(at -0.889 0 90)
			(size 1.016 1.27)
			(layers "B.Cu" "B.Mask" "B.Paste")
			(net "GND")
		)
	)
	(footprint ""
		(layer "B.Cu")
		(at 359.694988 -166.830756 90)
		(property "Reference" "PR355"
			(at 0 0 90)
			(layer "B.SilkS")
			(hide yes)
			(effects
				(font
					(size 1.27 1.27)
				)
				(justify mirror)
			)
		)
		(property "Value" ""
			(at 0 0 90)
			(layer "B.Fab")
			(effects
				(font
					(size 1.27 1.27)
				)
				(justify mirror)
			)
		)
		(duplicate_pad_numbers_are_jumpers no)
		(fp_line
			(start 0.7874 -0.4064)
			(end -0.7874 -0.4064)
			(stroke
				(width 0.1524)
				(type default)
			)
			(layer "B.SilkS")
		)
		(fp_line
			(start -0.7874 -0.4064)
			(end -0.7874 0.4064)
			(stroke
				(width 0.1524)
				(type default)
			)
			(layer "B.SilkS")
		)
		(fp_line
			(start 0.7874 0.4064)
			(end 0.7874 -0.4064)
			(stroke
				(width 0.1524)
				(type default)
			)
			(layer "B.SilkS")
		)
		(fp_line
			(start -0.7874 0.4064)
			(end 0.7874 0.4064)
			(stroke
				(width 0.1524)
				(type default)
			)
			(layer "B.SilkS")
		)
		(fp_line
			(start 0.67945 -0.305054)
			(end 0.12065 -0.305054)
			(stroke
				(width 0.1)
				(type default)
			)
			(layer "B.Fab")
		)
		(fp_line
			(start 0.12065 -0.305054)
			(end 0.12065 -0.2794)
			(stroke
				(width 0.1)
				(type default)
			)
			(layer "B.Fab")
		)
		(fp_line
			(start -0.12065 -0.3048)
			(end -0.67945 -0.3048)
			(stroke
				(width 0.1)
				(type default)
			)
			(layer "B.Fab")
		)
		(fp_line
			(start -0.67945 -0.3048)
			(end -0.67945 0.3048)
			(stroke
				(width 0.1)
				(type default)
			)
			(layer "B.Fab")
		)
		(fp_line
			(start 0.12065 -0.2794)
			(end -0.12065 -0.2794)
			(stroke
				(width 0.1)
				(type default)
			)
			(layer "B.Fab")
		)
		(fp_line
			(start -0.12065 -0.2794)
			(end -0.12065 -0.3048)
			(stroke
				(width 0.1)
				(type default)
			)
			(layer "B.Fab")
		)
		(fp_line
			(start 0.12065 0.2794)
			(end 0.12065 0.3048)
			(stroke
				(width 0.1)
				(type default)
			)
			(layer "B.Fab")
		)
		(fp_line
			(start -0.120396 0.2794)
			(end 0.12065 0.2794)
			(stroke
				(width 0.1)
				(type default)
			)
			(layer "B.Fab")
		)
		(fp_line
			(start 0.67945 0.3048)
			(end 0.67945 -0.305054)
			(stroke
				(width 0.1)
				(type default)
			)
			(layer "B.Fab")
		)
		(fp_line
			(start 0.12065 0.3048)
			(end 0.67945 0.3048)
			(stroke
				(width 0.1)
				(type default)
			)
			(layer "B.Fab")
		)
		(fp_line
			(start -0.120396 0.3048)
			(end -0.120396 0.2794)
			(stroke
				(width 0.1)
				(type default)
			)
			(layer "B.Fab")
		)
		(fp_line
			(start -0.67945 0.3048)
			(end -0.120396 0.3048)
			(stroke
				(width 0.1)
				(type default)
			)
			(layer "B.Fab")
		)
		(pad "1" smd circle
			(at 0.40005 0 270)
			(size 0 0)
			(layers "B.Cu" "B.Mask" "B.Paste")
			(net "PVDDCR_CPU0_P0_VOS5")
		)
		(pad "2" smd circle
			(at -0.40005 0 270)
			(size 0 0)
			(layers "B.Cu" "B.Mask" "B.Paste")
			(net "PVDDCR_CPU0_P0")
		)
	)
	(footprint ""
		(layer "B.Cu")
		(at 23.235158 -383.53873 -90)
		(property "Reference" "PC6815"
			(at 1.64973 -4.043172 270)
			(unlocked yes)
			(layer "B.SilkS")
			(effects
				(font
					(size 0.7874 0.5842)
					(thickness 0.1524)
				)
				(justify left mirror)
			)
		)
		(property "Value" ""
			(at 0 0 90)
			(layer "B.Fab")
			(effects
				(font
					(size 1.27 1.27)
				)
				(justify mirror)
			)
		)
		(duplicate_pad_numbers_are_jumpers no)
		(fp_line
			(start 4.83108 2.150364)
			(end 4.447794 2.149348)
			(stroke
				(width 0.1524)
				(type default)
			)
			(layer "B.SilkS")
		)
		(fp_line
			(start -4.53898 2.15011)
			(end 4.53898 2.15011)
			(stroke
				(width 0.1524)
				(type default)
			)
			(layer "B.SilkS")
		)
		(fp_line
			(start 4.53898 2.15011)
			(end 4.53898 -2.15011)
			(stroke
				(width 0.1524)
				(type default)
			)
			(layer "B.SilkS")
		)
		(fp_line
			(start -4.53898 -2.15011)
			(end -4.53898 2.15011)
			(stroke
				(width 0.1524)
				(type default)
			)
			(layer "B.SilkS")
		)
		(fp_line
			(start 4.53898 -2.15011)
			(end -4.53898 -2.15011)
			(stroke
				(width 0.1524)
				(type default)
			)
			(layer "B.SilkS")
		)
		(fp_line
			(start 4.53898 -2.150618)
			(end 4.539742 2.152142)
			(stroke
				(width 0.1524)
				(type default)
			)
			(layer "B.SilkS")
		)
		(fp_line
			(start 4.69138 -2.150618)
			(end 4.692396 2.161032)
			(stroke
				(width 0.1524)
				(type default)
			)
			(layer "B.SilkS")
		)
		(fp_line
			(start 4.84378 -2.150618)
			(end 4.842256 2.163064)
			(stroke
				(width 0.1524)
				(type default)
			)
			(layer "B.SilkS")
		)
		(fp_line
			(start 4.84378 -2.150618)
			(end 4.53898 -2.150618)
			(stroke
				(width 0.1524)
				(type default)
			)
			(layer "B.SilkS")
		)
		(fp_line
			(start -3.64998 2.15011)
			(end 3.64998 2.15011)
			(stroke
				(width 0.1)
				(type default)
			)
			(layer "B.Fab")
		)
		(fp_line
			(start 3.64998 2.15011)
			(end 3.64998 -2.15011)
			(stroke
				(width 0.1)
				(type default)
			)
			(layer "B.Fab")
		)
		(fp_line
			(start -3.64998 -2.15011)
			(end -3.64998 2.15011)
			(stroke
				(width 0.1)
				(type default)
			)
			(layer "B.Fab")
		)
		(fp_line
			(start 3.64998 -2.15011)
			(end -3.64998 -2.15011)
			(stroke
				(width 0.1)
				(type default)
			)
			(layer "B.Fab")
		)
		(fp_text user "+"
			(at 6.87451 1.371854 270)
			(unlocked yes)
			(layer "B.SilkS")
			(effects
				(font
					(size 1.905 1.4224)
					(thickness 0.1524)
				)
				(justify left mirror)
			)
		)
		(fp_text user "-"
			(at -4.313174 -0.094488 270)
			(unlocked yes)
			(layer "B.SilkS")
			(effects
				(font
					(size 1.905 1.4224)
					(thickness 0.1524)
				)
				(justify left mirror)
			)
		)
		(fp_text user "-"
			(at -4.313174 -0.094488 270)
			(unlocked yes)
			(layer "B.Fab")
			(effects
				(font
					(size 1.905 1.4224)
					(thickness 0.1524)
				)
				(justify left mirror)
			)
		)
		(fp_text user "+"
			(at 6.214872 -0.337058 270)
			(unlocked yes)
			(layer "B.Fab")
			(effects
				(font
					(size 1.905 1.4224)
					(thickness 0.1524)
				)
				(justify left mirror)
			)
		)
		(pad "1" smd rect
			(at 3.199892 0 90)
			(size 2.413 2.8194)
			(layers "B.Cu" "B.Mask" "B.Paste")
			(net "P0V9_CPU1_RT_2D")
		)
		(pad "2" smd rect
			(at -3.199892 0 90)
			(size 2.413 2.8194)
			(layers "B.Cu" "B.Mask" "B.Paste")
			(net "GND")
		)
	)
)
